# S9S_MB_2U (Grand Teton) — schematic netlist excerpt (pin names and nets, part order shuffled) for the footprints in the layout excerpt that follows; sources: Cadence DE-HDL packaged netlist, KiCad conversion of 03242023_DA0F0TMBIJ0_F0T_Motherboard_J_brd_V01_OCP.brd

C921  Q_CAP_DIFFBUS  DIFF BUS_0.22UF 6.3V 20% X6S  pkg C0201  page 173 : \1\ = P5E_CPU0_PE0_TX_C_DP<6> ; \2\ = P5E_CPU0_PE0_TX_DP<6>
PR3935  Q_RES  10K 1% CHIP  pkg 0402LF  page 301 : A = HSC_VTEMP ; B = AGND_HSC
C1104  Q_CAP_DIFFBUS  DIFF BUS_0.22UF 6.3V 20% X6S  pkg C0201  page 181 : \1\ = P3E_PCH_M2_TX_DP<0> ; \2\ = P3E_PCH_M2_TX_C_DP<0>

(kicad_pcb
	(version 20260206)
	(generator "pcbnew")
	(generator_version "10.0")
	(general
		(thickness 1.6)
		(legacy_teardrops no)
	)
	(paper "A4")
	(title_block
		(title "03242023_DA0F0TMBIJ0_F0T_Motherboard_J_brd_V01_OCP.brd")
		(comment 1 "Grand Teton / footprints 2018-2020 of 6105")
	)
	(layers
		(0 "F.Cu" signal "TOP")
		(4 "In1.Cu" signal "GND")
		(6 "In2.Cu" signal "IN1")
		(8 "In3.Cu" signal "GND1")
		(10 "In4.Cu" signal "IN2")
		(12 "In5.Cu" signal "GND2")
		(14 "In6.Cu" signal "IN3")
		(16 "In7.Cu" signal "GND3")
		(18 "In8.Cu" signal "VCC")
		(20 "In9.Cu" signal "VCC1")
		(22 "In10.Cu" signal "GND4")
		(24 "In11.Cu" signal "IN4")
		(26 "In12.Cu" signal "GND5")
		(28 "In13.Cu" signal "IN5")
		(30 "In14.Cu" signal "GND6")
		(32 "In15.Cu" signal "IN6")
		(34 "In16.Cu" signal "GND7")
		(2 "B.Cu" signal "BOTTOM")
		(9 "F.Adhes" user "F.Adhesive")
		(11 "B.Adhes" user "B.Adhesive")
		(13 "F.Paste" user "Package Geometry/Pastemask Top")
		(15 "B.Paste" user "Package Geometry/Pastemask Bottom")
		(5 "F.SilkS" user "Ref Des/Silkscreen Top")
		(7 "B.SilkS" user "Ref Des/Silkscreen Bottom")
		(1 "F.Mask" user "Board Geometry/Soldermask Top")
		(3 "B.Mask" user "Board Geometry/Soldermask Bottom")
		(17 "Dwgs.User" user "User.Drawings")
		(19 "Cmts.User" user "User.Comments")
		(21 "Eco1.User" user "User.Eco1")
		(23 "Eco2.User" user "User.Eco2")
		(25 "Edge.Cuts" user "Board Geometry/Outline")
		(27 "Margin" user)
		(31 "F.CrtYd" user "Package Geometry/Place Bound Top")
		(29 "B.CrtYd" user "Package Geometry/Place Bound Bottom")
		(35 "F.Fab" user "Ref Des/Assembly Top")
		(33 "B.Fab" user "Ref Des/Assembly Bottom")
	)
	(footprint ""
		(layer "F.Cu")
		(at 180.528468 -53.980334 180)
		(property "Reference" "C1104"
			(at 0 0 180)
			(layer "F.SilkS")
			(hide yes)
			(effects
				(font
					(size 1.27 1.27)
				)
			)
		)
		(property "Value" ""
			(at 0 0 180)
			(layer "F.Fab")
			(effects
				(font
					(size 1.27 1.27)
				)
			)
		)
		(duplicate_pad_numbers_are_jumpers no)
		(fp_line
			(start 0.299974 0.150114)
			(end -0.299974 0.150114)
			(stroke
				(width 0.1)
				(type default)
			)
			(layer "F.Fab")
		)
		(fp_line
			(start 0.299974 -0.150114)
			(end 0.299974 0.150114)
			(stroke
				(width 0.1)
				(type default)
			)
			(layer "F.Fab")
		)
		(fp_line
			(start -0.299974 0.150114)
			(end -0.299974 -0.150114)
			(stroke
				(width 0.1)
				(type default)
			)
			(layer "F.Fab")
		)
		(fp_line
			(start -0.299974 -0.150114)
			(end 0.299974 -0.150114)
			(stroke
				(width 0.1)
				(type default)
			)
			(layer "F.Fab")
		)
		(pad "1" smd rect
			(at -0.2667 0 180)
			(size 0.3048 0.381)
			(layers "F.Cu" "F.Mask" "F.Paste")
			(net "P3E_PCH_M2_TX_DP<0>")
		)
		(pad "2" smd rect
			(at 0.2667 0 180)
			(size 0.3048 0.381)
			(layers "F.Cu" "F.Mask" "F.Paste")
			(net "P3E_PCH_M2_TX_C_DP<0>")
		)
		(zone
			(layer "In1.Cu")
			(hatch none 0.5)
			(connect_pads
				(clearance 0)
			)
			(min_thickness 0.25)
			(keepout
				(tracks not_allowed)
				(vias allowed)
				(pads allowed)
				(copperpour not_allowed)
				(footprints allowed)
			)
			(placement
				(enabled no)
				(sheetname "")
			)
			(fill
				(thermal_gap 0.5)
				(thermal_bridge_width 0.5)
				(island_removal_mode 0)
			)
			(polygon
				(pts
					(arc
						(start 180.388768 -54.221634)
						(mid 180.44265 -54.199316)
						(end 180.464968 -54.145434)
					)
					(arc
						(start 180.464968 -53.815234)
						(mid 180.44265 -53.761352)
						(end 180.388768 -53.739034)
					)
					(arc
						(start 180.134768 -53.739034)
						(mid 180.080886 -53.761352)
						(end 180.058568 -53.815234)
					)
					(arc
						(start 180.058568 -54.145434)
						(mid 180.080886 -54.199316)
						(end 180.134768 -54.221634)
					)
				)
			)
		)
		(zone
			(layer "In1.Cu")
			(hatch none 0.5)
			(connect_pads
				(clearance 0)
			)
			(min_thickness 0.25)
			(keepout
				(tracks not_allowed)
				(vias allowed)
				(pads allowed)
				(copperpour not_allowed)
				(footprints allowed)
			)
			(placement
				(enabled no)
				(sheetname "")
			)
			(fill
				(thermal_gap 0.5)
				(thermal_bridge_width 0.5)
				(island_removal_mode 0)
			)
			(polygon
				(pts
					(arc
						(start 180.922168 -54.221634)
						(mid 180.97605 -54.199316)
						(end 180.998368 -54.145434)
					)
					(arc
						(start 180.998368 -53.815234)
						(mid 180.97605 -53.761352)
						(end 180.922168 -53.739034)
					)
					(arc
						(start 180.668168 -53.739034)
						(mid 180.614286 -53.761352)
						(end 180.591968 -53.815234)
					)
					(arc
						(start 180.591968 -54.145434)
						(mid 180.614286 -54.199316)
						(end 180.668168 -54.221634)
					)
				)
			)
		)
	)
	(footprint ""
		(layer "F.Cu")
		(at 179.352448 -404.287482 180)
		(property "Reference" "PR3935"
			(at 0 0 180)
			(layer "F.SilkS")
			(hide yes)
			(effects
				(font
					(size 1.27 1.27)
				)
			)
		)
		(property "Value" ""
			(at 0 0 180)
			(layer "F.Fab")
			(effects
				(font
					(size 1.27 1.27)
				)
			)
		)
		(duplicate_pad_numbers_are_jumpers no)
		(fp_line
			(start 0.7874 0.4064)
			(end -0.7874 0.4064)
			(stroke
				(width 0.1524)
				(type default)
			)
			(layer "F.SilkS")
		)
		(fp_line
			(start 0.7874 -0.4064)
			(end 0.7874 0.4064)
			(stroke
				(width 0.1524)
				(type default)
			)
			(layer "F.SilkS")
		)
		(fp_line
			(start -0.7874 0.4064)
			(end -0.7874 -0.4064)
			(stroke
				(width 0.1524)
				(type default)
			)
			(layer "F.SilkS")
		)
		(fp_line
			(start -0.7874 -0.4064)
			(end 0.7874 -0.4064)
			(stroke
				(width 0.1524)
				(type default)
			)
			(layer "F.SilkS")
		)
		(fp_line
			(start 0.67945 0.3048)
			(end 0.120396 0.3048)
			(stroke
				(width 0.1)
				(type default)
			)
			(layer "F.Fab")
		)
		(fp_line
			(start 0.67945 -0.3048)
			(end 0.67945 0.3048)
			(stroke
				(width 0.1)
				(type default)
			)
			(layer "F.Fab")
		)
		(fp_line
			(start 0.12065 -0.2794)
			(end 0.12065 -0.3048)
			(stroke
				(width 0.1)
				(type default)
			)
			(layer "F.Fab")
		)
		(fp_line
			(start 0.12065 -0.3048)
			(end 0.67945 -0.3048)
			(stroke
				(width 0.1)
				(type default)
			)
			(layer "F.Fab")
		)
		(fp_line
			(start 0.120396 0.3048)
			(end 0.120396 0.2794)
			(stroke
				(width 0.1)
				(type default)
			)
			(layer "F.Fab")
		)
		(fp_line
			(start 0.120396 0.2794)
			(end -0.12065 0.2794)
			(stroke
				(width 0.1)
				(type default)
			)
			(layer "F.Fab")
		)
		(fp_line
			(start -0.12065 0.3048)
			(end -0.67945 0.3048)
			(stroke
				(width 0.1)
				(type default)
			)
			(layer "F.Fab")
		)
		(fp_line
			(start -0.12065 0.2794)
			(end -0.12065 0.3048)
			(stroke
				(width 0.1)
				(type default)
			)
			(layer "F.Fab")
		)
		(fp_line
			(start -0.12065 -0.2794)
			(end 0.12065 -0.2794)
			(stroke
				(width 0.1)
				(type default)
			)
			(layer "F.Fab")
		)
		(fp_line
			(start -0.12065 -0.305054)
			(end -0.12065 -0.2794)
			(stroke
				(width 0.1)
				(type default)
			)
			(layer "F.Fab")
		)
		(fp_line
			(start -0.67945 0.3048)
			(end -0.67945 -0.305054)
			(stroke
				(width 0.1)
				(type default)
			)
			(layer "F.Fab")
		)
		(fp_line
			(start -0.67945 -0.305054)
			(end -0.12065 -0.305054)
			(stroke
				(width 0.1)
				(type default)
			)
			(layer "F.Fab")
		)
		(pad "1" smd circle
			(at -0.40005 0 180)
			(size 0 0)
			(layers "F.Cu" "F.Mask" "F.Paste")
			(net "HSC_VTEMP")
		)
		(pad "2" smd circle
			(at 0.40005 0 180)
			(size 0 0)
			(layers "F.Cu" "F.Mask" "F.Paste")
			(net "AGND_HSC")
		)
	)
	(footprint ""
		(layer "F.Cu")
		(at 333.784448 -408.517344 -90)
		(property "Reference" "C921"
			(at 0 0 270)
			(layer "F.SilkS")
			(hide yes)
			(effects
				(font
					(size 1.27 1.27)
				)
			)
		)
		(property "Value" ""
			(at 0 0 270)
			(layer "F.Fab")
			(effects
				(font
					(size 1.27 1.27)
				)
			)
		)
		(duplicate_pad_numbers_are_jumpers no)
		(fp_line
			(start -0.299974 0.150114)
			(end -0.299974 -0.150114)
			(stroke
				(width 0.1)
				(type default)
			)
			(layer "F.Fab")
		)
		(fp_line
			(start 0.299974 0.150114)
			(end -0.299974 0.150114)
			(stroke
				(width 0.1)
				(type default)
			)
			(layer "F.Fab")
		)
		(fp_line
			(start -0.299974 -0.150114)
			(end 0.299974 -0.150114)
			(stroke
				(width 0.1)
				(type default)
			)
			(layer "F.Fab")
		)
		(fp_line
			(start 0.299974 -0.150114)
			(end 0.299974 0.150114)
			(stroke
				(width 0.1)
				(type default)
			)
			(layer "F.Fab")
		)
		(pad "1" smd rect
			(at -0.2667 0 270)
			(size 0.3048 0.381)
			(layers "F.Cu" "F.Mask" "F.Paste")
			(net "P5E_CPU0_PE0_TX_C_DP<6>")
		)
		(pad "2" smd rect
			(at 0.2667 0 270)
			(size 0.3048 0.381)
			(layers "F.Cu" "F.Mask" "F.Paste")
			(net "P5E_CPU0_PE0_TX_DP<6>")
		)
	)
)
